(kicad_pcb
	(version 20260206)
	(generator "pcbnew")
	(generator_version "10.0")
	(general
		(thickness 1.6)
		(legacy_teardrops no)
	)
	(paper "A4")
	(title_block
		(title "v1-chassis-manager — T6M_CM_d_v01_1031_1645.brd")
		(comment 1 "Open CloudServer (Microsoft) / footprint 81 of 2512 (U30), pads 1-77 of 77")
	)
	(layers
		(0 "F.Cu" signal "TOP")
		(4 "In1.Cu" signal "GND1")
		(6 "In2.Cu" signal "IN1")
		(8 "In3.Cu" signal "VCC1")
		(10 "In4.Cu" signal "VCC2")
		(12 "In5.Cu" signal "GND2")
		(14 "In6.Cu" signal "IN2")
		(16 "In7.Cu" signal "IN3")
		(18 "In8.Cu" signal "GND3")
		(2 "B.Cu" signal "BOTTOM")
		(9 "F.Adhes" user "F.Adhesive")
		(11 "B.Adhes" user "B.Adhesive")
		(13 "F.Paste" user "Package Geometry/Pastemask Top")
		(15 "B.Paste" user "Package Geometry/Pastemask Bottom")
		(5 "F.SilkS" user "Ref Des/Silkscreen Top")
		(7 "B.SilkS" user "Ref Des/Silkscreen Bottom")
		(1 "F.Mask" user "Board Geometry/Soldermask Top")
		(3 "B.Mask" user "Board Geometry/Soldermask Bottom")
		(17 "Dwgs.User" user "User.Drawings")
		(19 "Cmts.User" user "User.Comments")
		(21 "Eco1.User" user "User.Eco1")
		(23 "Eco2.User" user "User.Eco2")
		(25 "Edge.Cuts" user "Board Geometry/Outline")
		(27 "Margin" user)
		(31 "F.CrtYd" user "Package Geometry/Place Bound Top")
		(29 "B.CrtYd" user "Package Geometry/Place Bound Bottom")
		(35 "F.Fab" user "Ref Des/Assembly Top")
		(33 "B.Fab" user "Ref Des/Assembly Bottom")
	)
	(footprint ""
		(layer "F.Cu")
		(at 141.530578 -59.916822 90)
		(property "Reference" "U30"
			(at 10.669016 3.15341 0)
			(unlocked yes)
			(layer "F.SilkS")
			(effects
				(font
					(size 0.7874 0.5842)
					(thickness 0.1524)
				)
				(justify left)
			)
		)
		(property "Value" ""
			(at 0 0 90)
			(layer "F.Fab")
			(effects
				(font
					(size 1.27 1.27)
				)
			)
		)
		(duplicate_pad_numbers_are_jumpers no)
		(pad "1" smd rect
			(at 0 0 180)
			(size 0.1778 1.1176)
			(layers "F.Cu" "F.Mask" "F.Paste")
			(net "Net_1786")
		)
		(pad "2" smd rect
			(at 0 0.40005 180)
			(size 0.1778 1.1176)
			(layers "F.Cu" "F.Mask" "F.Paste")
			(net "Net_1793")
		)
		(pad "3" smd rect
			(at 0 0.8001 180)
			(size 0.1778 1.1176)
			(layers "F.Cu" "F.Mask" "F.Paste")
			(net "Net_1794")
		)
		(pad "4" smd rect
			(at 0 1.199896 180)
			(size 0.1778 1.1176)
			(layers "F.Cu" "F.Mask" "F.Paste")
			(net "Net_1795")
		)
		(pad "5" smd rect
			(at 0 1.599946 180)
			(size 0.1778 1.1176)
			(layers "F.Cu" "F.Mask" "F.Paste")
			(net "P1V0_SATA")
		)
		(pad "6" smd rect
			(at 0 1.999996 180)
			(size 0.1778 1.1176)
			(layers "F.Cu" "F.Mask" "F.Paste")
			(net "Net_1800")
		)
		(pad "7" smd rect
			(at 0 2.400046 180)
			(size 0.1778 1.1176)
			(layers "F.Cu" "F.Mask" "F.Paste")
			(net "Net_1810")
		)
		(pad "8" smd rect
			(at 0 2.800096 180)
			(size 0.1778 1.1176)
			(layers "F.Cu" "F.Mask" "F.Paste")
			(net "Net_1814")
		)
		(pad "9" smd rect
			(at 0 3.199892 180)
			(size 0.1778 1.1176)
			(layers "F.Cu" "F.Mask" "F.Paste")
			(net "P3V3_NODE1")
		)
		(pad "10" smd rect
			(at 0 3.599942 180)
			(size 0.1778 1.1176)
			(layers "F.Cu" "F.Mask" "F.Paste")
			(net "Net_1787")
		)
		(pad "11" smd rect
			(at 0 3.999992 180)
			(size 0.1778 1.1176)
			(layers "F.Cu" "F.Mask" "F.Paste")
			(net "Net_1788")
		)
		(pad "12" smd rect
			(at 0 4.400042 180)
			(size 0.1778 1.1176)
			(layers "F.Cu" "F.Mask" "F.Paste")
			(net "Net_1789")
		)
		(pad "13" smd rect
			(at 0 4.800092 180)
			(size 0.1778 1.1176)
			(layers "F.Cu" "F.Mask" "F.Paste")
			(net "P1V0_SATA")
		)
		(pad "14" smd rect
			(at 0 5.199888 180)
			(size 0.1778 1.1176)
			(layers "F.Cu" "F.Mask" "F.Paste")
			(net "Net_1790")
		)
		(pad "15" smd rect
			(at 0 5.599938 180)
			(size 0.1778 1.1176)
			(layers "F.Cu" "F.Mask" "F.Paste")
			(net "Net_1791")
		)
		(pad "16" smd rect
			(at 0 5.999988 180)
			(size 0.1778 1.1176)
			(layers "F.Cu" "F.Mask" "F.Paste")
			(net "Net_1792")
		)
		(pad "17" smd rect
			(at 0 6.400038 180)
			(size 0.1778 1.1176)
			(layers "F.Cu" "F.Mask" "F.Paste")
			(net "SATA_NODE1_GPIO3")
		)
		(pad "18" smd rect
			(at 0 6.800088 180)
			(size 0.1778 1.1176)
			(layers "F.Cu" "F.Mask" "F.Paste")
			(net "PU_SATA_NODE1_GPIO4")
		)
		(pad "19" smd rect
			(at 0 7.199884 180)
			(size 0.1778 1.1176)
			(layers "F.Cu" "F.Mask" "F.Paste")
			(net "SATA_NODE1_GPIO5")
		)
		(pad "20" smd rect
			(at 0.841248 8.041132 90)
			(size 0.1778 1.1176)
			(layers "F.Cu" "F.Mask" "F.Paste")
			(net "NODE1_USB_TESTMODE")
		)
		(pad "21" smd rect
			(at 1.241298 8.041132 90)
			(size 0.1778 1.1176)
			(layers "F.Cu" "F.Mask" "F.Paste")
			(net "P1V0_SATA")
		)
		(pad "22" smd rect
			(at 1.641094 8.041132 90)
			(size 0.1778 1.1176)
			(layers "F.Cu" "F.Mask" "F.Paste")
			(net "TP_SATA_NODE1")
		)
		(pad "23" smd rect
			(at 2.041144 8.041132 90)
			(size 0.1778 1.1176)
			(layers "F.Cu" "F.Mask" "F.Paste")
			(net "Net_1816")
		)
		(pad "24" smd rect
			(at 2.441194 8.041132 90)
			(size 0.1778 1.1176)
			(layers "F.Cu" "F.Mask" "F.Paste")
			(net "Net_1815")
		)
		(pad "25" smd rect
			(at 2.841244 8.041132 90)
			(size 0.1778 1.1176)
			(layers "F.Cu" "F.Mask" "F.Paste")
			(net "P1V8_SATA_VAA2_1_NODE1")
		)
		(pad "26" smd rect
			(at 3.241294 8.041132 90)
			(size 0.1778 1.1176)
			(layers "F.Cu" "F.Mask" "F.Paste")
			(net "Net_1817")
		)
		(pad "27" smd rect
			(at 3.64109 8.041132 90)
			(size 0.1778 1.1176)
			(layers "F.Cu" "F.Mask" "F.Paste")
			(net "Net_1818")
		)
		(pad "28" smd rect
			(at 4.04114 8.041132 90)
			(size 0.1778 1.1176)
			(layers "F.Cu" "F.Mask" "F.Paste")
			(net "GND")
		)
		(pad "29" smd rect
			(at 4.44119 8.041132 90)
			(size 0.1778 1.1176)
			(layers "F.Cu" "F.Mask" "F.Paste")
			(net "SATA_A_NODE1_RX_P0")
		)
		(pad "30" smd rect
			(at 4.84124 8.041132 90)
			(size 0.1778 1.1176)
			(layers "F.Cu" "F.Mask" "F.Paste")
			(net "SATA_A_NODE1_RX_N0")
		)
		(pad "31" smd rect
			(at 5.24129 8.041132 90)
			(size 0.1778 1.1176)
			(layers "F.Cu" "F.Mask" "F.Paste")
			(net "P1V8_SATA_VAA2_0_NODE1")
		)
		(pad "32" smd rect
			(at 5.641086 8.041132 90)
			(size 0.1778 1.1176)
			(layers "F.Cu" "F.Mask" "F.Paste")
			(net "SATA_A_NODE1_TX_N0")
		)
		(pad "33" smd rect
			(at 6.041136 8.041132 90)
			(size 0.1778 1.1176)
			(layers "F.Cu" "F.Mask" "F.Paste")
			(net "SATA_A_NODE1_TX_P0")
		)
		(pad "34" smd rect
			(at 6.441186 8.041132 90)
			(size 0.1778 1.1176)
			(layers "F.Cu" "F.Mask" "F.Paste")
			(net "P1V8_SATA_VAA1_NODE1")
		)
		(pad "35" smd rect
			(at 6.841236 8.041132 90)
			(size 0.1778 1.1176)
			(layers "F.Cu" "F.Mask" "F.Paste")
			(net "CLK_25M_SATA_NODE1")
		)
		(pad "36" smd rect
			(at 7.241286 8.041132 90)
			(size 0.1778 1.1176)
			(layers "F.Cu" "F.Mask" "F.Paste")
			(net "SATA_NODE1_XTLOUT")
		)
		(pad "37" smd rect
			(at 7.641082 8.041132 90)
			(size 0.1778 1.1176)
			(layers "F.Cu" "F.Mask" "F.Paste")
			(net "SATA_NODE1_ISET")
		)
		(pad "38" smd rect
			(at 8.041132 8.041132 90)
			(size 0.1778 1.1176)
			(layers "F.Cu" "F.Mask" "F.Paste")
			(net "SATA_VCONT_NODE1")
		)
		(pad "39" smd rect
			(at 8.88238 7.199884 180)
			(size 0.1778 1.1176)
			(layers "F.Cu" "F.Mask" "F.Paste")
			(net "P2E_CPU_SATA_NODE1_RX_C_DN")
		)
		(pad "40" smd rect
			(at 8.88238 6.800088 180)
			(size 0.1778 1.1176)
			(layers "F.Cu" "F.Mask" "F.Paste")
			(net "P2E_CPU_SATA_NODE1_RX_C_DP")
		)
		(pad "41" smd rect
			(at 8.88238 6.400038 180)
			(size 0.1778 1.1176)
			(layers "F.Cu" "F.Mask" "F.Paste")
			(net "P1V8_SATA_AVDD_NODE1")
		)
		(pad "42" smd rect
			(at 8.88238 5.999988 180)
			(size 0.1778 1.1176)
			(layers "F.Cu" "F.Mask" "F.Paste")
			(net "P1V8_SATA_AVDD_NODE1")
		)
		(pad "43" smd rect
			(at 8.88238 5.599938 180)
			(size 0.1778 1.1176)
			(layers "F.Cu" "F.Mask" "F.Paste")
			(net "P2E_CPU_SATA_NODE1_TX_DN")
		)
		(pad "44" smd rect
			(at 8.88238 5.199888 180)
			(size 0.1778 1.1176)
			(layers "F.Cu" "F.Mask" "F.Paste")
			(net "P2E_CPU_SATA_NODE1_TX_DP")
		)
		(pad "45" smd rect
			(at 8.88238 4.800092 180)
			(size 0.1778 1.1176)
			(layers "F.Cu" "F.Mask" "F.Paste")
			(net "CLK_100M_SATA_NODE1_DP")
		)
		(pad "46" smd rect
			(at 8.88238 4.400042 180)
			(size 0.1778 1.1176)
			(layers "F.Cu" "F.Mask" "F.Paste")
			(net "CLK_100M_SATA_NODE1_DN")
		)
		(pad "47" smd rect
			(at 8.88238 3.999992 180)
			(size 0.1778 1.1176)
			(layers "F.Cu" "F.Mask" "F.Paste")
			(net "SATA_SPI_DO_NODE1_R")
		)
		(pad "48" smd rect
			(at 8.88238 3.599942 180)
			(size 0.1778 1.1176)
			(layers "F.Cu" "F.Mask" "F.Paste")
			(net "SATA_SPI_CS_NODE1_R")
		)
		(pad "49" smd rect
			(at 8.88238 3.199892 180)
			(size 0.1778 1.1176)
			(layers "F.Cu" "F.Mask" "F.Paste")
			(net "SATA_SPI_DI_NODE1")
		)
		(pad "50" smd rect
			(at 8.88238 2.800096 180)
			(size 0.1778 1.1176)
			(layers "F.Cu" "F.Mask" "F.Paste")
			(net "SATA_SPI_CLK_NODE1_R")
		)
		(pad "51" smd rect
			(at 8.88238 2.400046 180)
			(size 0.1778 1.1176)
			(layers "F.Cu" "F.Mask" "F.Paste")
			(net "P1V0_SATA")
		)
		(pad "52" smd rect
			(at 8.88238 1.999996 180)
			(size 0.1778 1.1176)
			(layers "F.Cu" "F.Mask" "F.Paste")
			(net "IRQ_LVC3_SATA_NODE1_WAKE_L")
		)
		(pad "53" smd rect
			(at 8.88238 1.599946 180)
			(size 0.1778 1.1176)
			(layers "F.Cu" "F.Mask" "F.Paste")
			(net "FM_CPLD_NODE1_SATA_PERST_L")
		)
		(pad "54" smd rect
			(at 8.88238 1.199896 180)
			(size 0.1778 1.1176)
			(layers "F.Cu" "F.Mask" "F.Paste")
			(net "LED_SATA_NODE1_GPIO0")
		)
		(pad "55" smd rect
			(at 8.88238 0.8001 180)
			(size 0.1778 1.1176)
			(layers "F.Cu" "F.Mask" "F.Paste")
			(net "Net_1796")
		)
		(pad "56" smd rect
			(at 8.88238 0.40005 180)
			(size 0.1778 1.1176)
			(layers "F.Cu" "F.Mask" "F.Paste")
			(net "Net_1797")
		)
		(pad "57" smd rect
			(at 8.88238 0 180)
			(size 0.1778 1.1176)
			(layers "F.Cu" "F.Mask" "F.Paste")
			(net "P3V3_NODE1")
		)
		(pad "58" smd rect
			(at 8.041132 -0.841248 90)
			(size 0.1778 1.1176)
			(layers "F.Cu" "F.Mask" "F.Paste")
			(net "Net_1798")
		)
		(pad "59" smd rect
			(at 7.641082 -0.841248 90)
			(size 0.1778 1.1176)
			(layers "F.Cu" "F.Mask" "F.Paste")
			(net "Net_1799")
		)
		(pad "60" smd rect
			(at 7.241286 -0.841248 90)
			(size 0.1778 1.1176)
			(layers "F.Cu" "F.Mask" "F.Paste")
			(net "Net_1801")
		)
		(pad "61" smd rect
			(at 6.841236 -0.841248 90)
			(size 0.1778 1.1176)
			(layers "F.Cu" "F.Mask" "F.Paste")
			(net "Net_1802")
		)
		(pad "62" smd rect
			(at 6.441186 -0.841248 90)
			(size 0.1778 1.1176)
			(layers "F.Cu" "F.Mask" "F.Paste")
			(net "Net_1803")
		)
		(pad "63" smd rect
			(at 6.041136 -0.841248 90)
			(size 0.1778 1.1176)
			(layers "F.Cu" "F.Mask" "F.Paste")
			(net "Net_1804")
		)
		(pad "64" smd rect
			(at 5.641086 -0.841248 90)
			(size 0.1778 1.1176)
			(layers "F.Cu" "F.Mask" "F.Paste")
			(net "P1V0_SATA")
		)
		(pad "65" smd rect
			(at 5.24129 -0.841248 90)
			(size 0.1778 1.1176)
			(layers "F.Cu" "F.Mask" "F.Paste")
			(net "Net_1805")
		)
		(pad "66" smd rect
			(at 4.84124 -0.841248 90)
			(size 0.1778 1.1176)
			(layers "F.Cu" "F.Mask" "F.Paste")
			(net "Net_1806")
		)
		(pad "67" smd rect
			(at 4.44119 -0.841248 90)
			(size 0.1778 1.1176)
			(layers "F.Cu" "F.Mask" "F.Paste")
			(net "Net_1807")
		)
		(pad "68" smd rect
			(at 4.04114 -0.841248 90)
			(size 0.1778 1.1176)
			(layers "F.Cu" "F.Mask" "F.Paste")
			(net "Net_1808")
		)
		(pad "69" smd rect
			(at 3.64109 -0.841248 90)
			(size 0.1778 1.1176)
			(layers "F.Cu" "F.Mask" "F.Paste")
			(net "Net_1809")
		)
		(pad "70" smd rect
			(at 3.241294 -0.841248 90)
			(size 0.1778 1.1176)
			(layers "F.Cu" "F.Mask" "F.Paste")
			(net "Net_1811")
		)
		(pad "71" smd rect
			(at 2.841244 -0.841248 90)
			(size 0.1778 1.1176)
			(layers "F.Cu" "F.Mask" "F.Paste")
			(net "P1V0_SATA")
		)
		(pad "72" smd rect
			(at 2.441194 -0.841248 90)
			(size 0.1778 1.1176)
			(layers "F.Cu" "F.Mask" "F.Paste")
			(net "Net_1812")
		)
		(pad "73" smd rect
			(at 2.041144 -0.841248 90)
			(size 0.1778 1.1176)
			(layers "F.Cu" "F.Mask" "F.Paste")
			(net "P3V3_NODE1")
		)
		(pad "74" smd rect
			(at 1.641094 -0.841248 90)
			(size 0.1778 1.1176)
			(layers "F.Cu" "F.Mask" "F.Paste")
			(net "SATA_NODE1_GPIO1")
		)
		(pad "75" smd rect
			(at 1.241298 -0.841248 90)
			(size 0.1778 1.1176)
			(layers "F.Cu" "F.Mask" "F.Paste")
			(net "SATA_NODE1_GPIO2")
		)
		(pad "76" smd rect
			(at 0.841248 -0.841248 90)
			(size 0.1778 1.1176)
			(layers "F.Cu" "F.Mask" "F.Paste")
			(net "Net_1813")
		)
		(pad "TH" smd rect
			(at 4.44119 3.599942 90)
			(size 3.9624 3.9624)
			(layers "F.Cu" "F.Mask" "F.Paste")
			(net "GND")
		)
	)
)
